# T6G (Grand Teton) — schematic netlist excerpt (pin names and nets, part order shuffled) for the footprints in the layout excerpt that follows; sources: Cadence DE-HDL packaged netlist, KiCad conversion of 04192023_DAF0TMB3IC0_F0TG_MB_C_brd_V02_OCP.brd

R810  Q_RES  1K 1% CHIP  pkg 0201LF  page 185 : A = P1V8_CPU1_RT_1D ; B = SMB_RT_CPU1_P3_ROM_R_SDA
C6083  Q_CAP  0.1UF 25V 10% X7R  pkg 0402  page 176 : A = P3V3_AUX ; B = GND
C6024  Q_CAP  0.1UF 25V 10% X7R  pkg 0402  page 180 : A = USB3_CPU0_BMC_HUB1_TX_DN ; B = USB3_CPU0_BMC_TX_BUF_C_DN

(kicad_pcb
	(version 20260206)
	(generator "pcbnew")
	(generator_version "10.0")
	(general
		(thickness 1.6)
		(legacy_teardrops no)
	)
	(paper "A4")
	(title_block
		(title "04192023_DAF0TMB3IC0_F0TG_MB_C_brd_V02_OCP.brd")
		(comment 1 "Grand Teton / footprints 1447-1449 of 8354")
	)
	(layers
		(0 "F.Cu" signal "TOP")
		(4 "In1.Cu" signal "GND")
		(6 "In2.Cu" signal "IN1")
		(8 "In3.Cu" signal "GND1")
		(10 "In4.Cu" signal "IN2")
		(12 "In5.Cu" signal "GND2")
		(14 "In6.Cu" signal "IN3")
		(16 "In7.Cu" signal "GND3")
		(18 "In8.Cu" signal "VCC")
		(20 "In9.Cu" signal "VCC1")
		(22 "In10.Cu" signal "GND4")
		(24 "In11.Cu" signal "IN4")
		(26 "In12.Cu" signal "GND5")
		(28 "In13.Cu" signal "IN5")
		(30 "In14.Cu" signal "GND6")
		(32 "In15.Cu" signal "IN6")
		(34 "In16.Cu" signal "GND7")
		(2 "B.Cu" signal "BOTTOM")
		(9 "F.Adhes" user "F.Adhesive")
		(11 "B.Adhes" user "B.Adhesive")
		(13 "F.Paste" user "Package Geometry/Pastemask Top")
		(15 "B.Paste" user "Package Geometry/Pastemask Bottom")
		(5 "F.SilkS" user "Ref Des/Silkscreen Top")
		(7 "B.SilkS" user "Ref Des/Silkscreen Bottom")
		(1 "F.Mask" user "Board Geometry/Soldermask Top")
		(3 "B.Mask" user "Board Geometry/Soldermask Bottom")
		(17 "Dwgs.User" user "User.Drawings")
		(19 "Cmts.User" user "User.Comments")
		(21 "Eco1.User" user "User.Eco1")
		(23 "Eco2.User" user "User.Eco2")
		(25 "Edge.Cuts" user "Board Geometry/Outline")
		(27 "Margin" user)
		(31 "F.CrtYd" user "Package Geometry/Place Bound Top")
		(29 "B.CrtYd" user "Package Geometry/Place Bound Bottom")
		(35 "F.Fab" user "Ref Des/Assembly Top")
		(33 "B.Fab" user "Ref Des/Assembly Bottom")
	)
	(footprint ""
		(layer "F.Cu")
		(at 114.52987 -68.811394)
		(property "Reference" "C6083"
			(at 0 0 0)
			(layer "F.SilkS")
			(hide yes)
			(effects
				(font
					(size 1.27 1.27)
				)
			)
		)
		(property "Value" ""
			(at 0 0 0)
			(layer "F.Fab")
			(effects
				(font
					(size 1.27 1.27)
				)
			)
		)
		(duplicate_pad_numbers_are_jumpers no)
		(fp_line
			(start -0.7874 -0.4064)
			(end 0.7874 -0.4064)
			(stroke
				(width 0.1524)
				(type default)
			)
			(layer "F.SilkS")
		)
		(fp_line
			(start -0.7874 0.4064)
			(end -0.7874 -0.4064)
			(stroke
				(width 0.1524)
				(type default)
			)
			(layer "F.SilkS")
		)
		(fp_line
			(start 0.7874 -0.4064)
			(end 0.7874 0.4064)
			(stroke
				(width 0.1524)
				(type default)
			)
			(layer "F.SilkS")
		)
		(fp_line
			(start 0.7874 0.4064)
			(end -0.7874 0.4064)
			(stroke
				(width 0.1524)
				(type default)
			)
			(layer "F.SilkS")
		)
		(fp_line
			(start -0.67945 -0.305054)
			(end -0.12065 -0.305054)
			(stroke
				(width 0.1)
				(type default)
			)
			(layer "F.Fab")
		)
		(fp_line
			(start -0.67945 0.3048)
			(end -0.67945 -0.305054)
			(stroke
				(width 0.1)
				(type default)
			)
			(layer "F.Fab")
		)
		(fp_line
			(start -0.12065 -0.305054)
			(end -0.12065 -0.2794)
			(stroke
				(width 0.1)
				(type default)
			)
			(layer "F.Fab")
		)
		(fp_line
			(start -0.12065 -0.2794)
			(end 0.12065 -0.2794)
			(stroke
				(width 0.1)
				(type default)
			)
			(layer "F.Fab")
		)
		(fp_line
			(start -0.12065 0.2794)
			(end -0.12065 0.3048)
			(stroke
				(width 0.1)
				(type default)
			)
			(layer "F.Fab")
		)
		(fp_line
			(start -0.12065 0.3048)
			(end -0.67945 0.3048)
			(stroke
				(width 0.1)
				(type default)
			)
			(layer "F.Fab")
		)
		(fp_line
			(start 0.120396 0.2794)
			(end -0.12065 0.2794)
			(stroke
				(width 0.1)
				(type default)
			)
			(layer "F.Fab")
		)
		(fp_line
			(start 0.120396 0.3048)
			(end 0.120396 0.2794)
			(stroke
				(width 0.1)
				(type default)
			)
			(layer "F.Fab")
		)
		(fp_line
			(start 0.12065 -0.3048)
			(end 0.67945 -0.3048)
			(stroke
				(width 0.1)
				(type default)
			)
			(layer "F.Fab")
		)
		(fp_line
			(start 0.12065 -0.2794)
			(end 0.12065 -0.3048)
			(stroke
				(width 0.1)
				(type default)
			)
			(layer "F.Fab")
		)
		(fp_line
			(start 0.67945 -0.3048)
			(end 0.67945 0.3048)
			(stroke
				(width 0.1)
				(type default)
			)
			(layer "F.Fab")
		)
		(fp_line
			(start 0.67945 0.3048)
			(end 0.120396 0.3048)
			(stroke
				(width 0.1)
				(type default)
			)
			(layer "F.Fab")
		)
		(pad "1" smd circle
			(at -0.40005 0)
			(size 0 0)
			(layers "F.Cu" "F.Mask" "F.Paste")
			(net "P3V3_AUX")
		)
		(pad "2" smd circle
			(at 0.40005 0)
			(size 0 0)
			(layers "F.Cu" "F.Mask" "F.Paste")
			(net "GND")
		)
	)
	(footprint ""
		(layer "F.Cu")
		(at 168.513506 -416.929316 90)
		(property "Reference" "R810"
			(at 0 0 90)
			(layer "F.SilkS")
			(hide yes)
			(effects
				(font
					(size 1.27 1.27)
				)
			)
		)
		(property "Value" ""
			(at 0 0 90)
			(layer "F.Fab")
			(effects
				(font
					(size 1.27 1.27)
				)
			)
		)
		(duplicate_pad_numbers_are_jumpers no)
		(fp_line
			(start 0.32512 -0.175006)
			(end 0.32512 0.175006)
			(stroke
				(width 0.1)
				(type default)
			)
			(layer "F.Fab")
		)
		(fp_line
			(start -0.32512 -0.175006)
			(end 0.32512 -0.175006)
			(stroke
				(width 0.1)
				(type default)
			)
			(layer "F.Fab")
		)
		(fp_line
			(start 0.32512 0.175006)
			(end -0.32512 0.175006)
			(stroke
				(width 0.1)
				(type default)
			)
			(layer "F.Fab")
		)
		(fp_line
			(start -0.32512 0.175006)
			(end -0.32512 -0.175006)
			(stroke
				(width 0.1)
				(type default)
			)
			(layer "F.Fab")
		)
		(pad "1" smd rect
			(at -0.2667 0 90)
			(size 0.3048 0.381)
			(layers "F.Cu" "F.Mask" "F.Paste")
			(net "P1V8_CPU1_RT_1D")
		)
		(pad "2" smd rect
			(at 0.2667 0 270)
			(size 0.3048 0.381)
			(layers "F.Cu" "F.Mask" "F.Paste")
			(net "SMB_RT_CPU1_P3_ROM_R_SDA")
		)
	)
	(footprint ""
		(layer "F.Cu")
		(at 123.35637 -35.430968 180)
		(property "Reference" "C6024"
			(at 0 0 180)
			(layer "F.SilkS")
			(hide yes)
			(effects
				(font
					(size 1.27 1.27)
				)
			)
		)
		(property "Value" ""
			(at 0 0 180)
			(layer "F.Fab")
			(effects
				(font
					(size 1.27 1.27)
				)
			)
		)
		(duplicate_pad_numbers_are_jumpers no)
		(fp_line
			(start 0.7874 0.4064)
			(end -0.7874 0.4064)
			(stroke
				(width 0.1524)
				(type default)
			)
			(layer "F.SilkS")
		)
		(fp_line
			(start 0.7874 -0.4064)
			(end 0.7874 0.4064)
			(stroke
				(width 0.1524)
				(type default)
			)
			(layer "F.SilkS")
		)
		(fp_line
			(start -0.7874 0.4064)
			(end -0.7874 -0.4064)
			(stroke
				(width 0.1524)
				(type default)
			)
			(layer "F.SilkS")
		)
		(fp_line
			(start -0.7874 -0.4064)
			(end 0.7874 -0.4064)
			(stroke
				(width 0.1524)
				(type default)
			)
			(layer "F.SilkS")
		)
		(fp_line
			(start 0.6858 0.3048)
			(end 0.1016 0.3048)
			(stroke
				(width 0.1)
				(type default)
			)
			(layer "F.Fab")
		)
		(fp_line
			(start 0.6858 -0.3048)
			(end 0.6858 0.3048)
			(stroke
				(width 0.1)
				(type default)
			)
			(layer "F.Fab")
		)
		(fp_line
			(start 0.1016 0.3048)
			(end 0.1016 0.2794)
			(stroke
				(width 0.1)
				(type default)
			)
			(layer "F.Fab")
		)
		(fp_line
			(start 0.1016 0.2794)
			(end -0.1016 0.2794)
			(stroke
				(width 0.1)
				(type default)
			)
			(layer "F.Fab")
		)
		(fp_line
			(start 0.1016 -0.2794)
			(end 0.1016 -0.3048)
			(stroke
				(width 0.1)
				(type default)
			)
			(layer "F.Fab")
		)
		(fp_line
			(start 0.1016 -0.3048)
			(end 0.6858 -0.3048)
			(stroke
				(width 0.1)
				(type default)
			)
			(layer "F.Fab")
		)
		(fp_line
			(start -0.1016 0.3048)
			(end -0.6858 0.3048)
			(stroke
				(width 0.1)
				(type default)
			)
			(layer "F.Fab")
		)
		(fp_line
			(start -0.1016 0.2794)
			(end -0.1016 0.3048)
			(stroke
				(width 0.1)
				(type default)
			)
			(layer "F.Fab")
		)
		(fp_line
			(start -0.1016 -0.2794)
			(end 0.1016 -0.2794)
			(stroke
				(width 0.1)
				(type default)
			)
			(layer "F.Fab")
		)
		(fp_line
			(start -0.1016 -0.3048)
			(end -0.1016 -0.2794)
			(stroke
				(width 0.1)
				(type default)
			)
			(layer "F.Fab")
		)
		(fp_line
			(start -0.6858 0.3048)
			(end -0.6858 -0.3048)
			(stroke
				(width 0.1)
				(type default)
			)
			(layer "F.Fab")
		)
		(fp_line
			(start -0.6858 -0.3048)
			(end -0.1016 -0.3048)
			(stroke
				(width 0.1)
				(type default)
			)
			(layer "F.Fab")
		)
		(pad "1" smd rect
			(at -0.40005 0)
			(size 0.4572 0.508)
			(layers "F.Cu" "F.Mask" "F.Paste")
			(net "USB3_CPU0_BMC_HUB1_TX_DN")
		)
		(pad "2" smd rect
			(at 0.40005 0)
			(size 0.4572 0.508)
			(layers "F.Cu" "F.Mask" "F.Paste")
			(net "USB3_CPU0_BMC_TX_BUF_C_DN")
		)
	)
)
